FILE_TYPE = MULTI_PHYS_TABLE;

PART 'CONN112_10137002101LF'

{========================================================================================}
:VALUE                    | PART_TYPE | MATERIAL | PART_NUMBER    = STANDARD        | LIFECYCLE     | PART_NUMBER   | JEDEC_TYPE              | DESCRIPTION                               | MANUFTR | MANUF_PN         | RD_CMPLS_LVL | CMPLS_LVL | CLASS | DIP_SMD | FROM_PJ      | DATA                 | FP_ECN | EE_CHECK_LIST | CREATOR | CREATEDAY  | PSL | STATUS | ESD_CDM | ESD_HBM | ESD_MM | MSD  | PIN_LENGTH_LONG_PIN | PIN_LENGTH_SHORT_PIN ;
{========================================================================================}
 'CONN112_10137002-101LF' | 'THLF'    | 'IO'     | 'DFHSB2FR012'(!) = ''               | ''               | 'DFHSB2FR012' |'HSD_F112D8_P2W1-2_RDH'| 'CONN DIP HOUSING 112P 8R FR(P1.2,H17.9)' | 'BER'   | '10137002-101LF' | 'EP(V1)'     | ''        | 'IO'  | 'DIP'   | 'JG5-ALBERT' | 'BER_10137002-101LF' | ''     | ''            | ''      | '20180413' | ''  | ''     | 'NA'    | 'NA'    | 'NA'   | 'NA' | '71 MILS'           | '63 MILS'           
 'CONN112_10137002-101LF' | 'THLF'    | 'EMPTY'  | 'DFHSB2FR012'(!) = ''               | ''               | 'DFHSB2FR012' |'HSD_F112D8_P2W1-2_RDH'| 'CONN DIP HOUSING 112P 8R FR(P1.2,H17.9)' | 'BER'   | '10137002-101LF' | 'EP(V1)'     | ''        | 'IO'  | 'DIP'   | 'JG5-ALBERT' | 'BER_10137002-101LF' | ''     | ''            | ''      | '20180413' | ''  | ''     | 'NA'    | 'NA'    | 'NA'   | 'NA' | '71 MILS'           | '63 MILS'           

END_PART

END.

